# BASEBOARD_FAB2 (Tioga Pass) — schematic netlist excerpt (pin names and nets, part order shuffled) for the footprints in the layout excerpt that follows; sources: Cadence DE-HDL packaged netlist, KiCad conversion of Wiwynn_Tioga_Pass_MB.brd

R7D24  RES  33.2 1% CHIP  pkg 0402  page 93 : A = FM_CPU1_PROCHOT_LVT3_K_N ; B = FM_CPU1_PROCHOT_LVT3_N
C8W3  CAP  100UF 4V 20% X5R  pkg 0805  page 42 : A = PVCCIN_CPU0 ; B = GND
C2L48  CAP_A  0.01UF 25V 10% X7R  pkg 0402V  page 173 : A = SATA6G_P6_TX_C_DP ; B = SATA6G_PCH_PCIE_UP_SATA_TXP<6>

(kicad_pcb
	(version 20260206)
	(generator "pcbnew")
	(generator_version "10.0")
	(general
		(thickness 1.6)
		(legacy_teardrops no)
	)
	(paper "A4")
	(title_block
		(title "Wiwynn_Tioga_Pass_MB.brd")
		(comment 1 "Tioga Pass / footprints 3323-3325 of 4770")
	)
	(layers
		(0 "F.Cu" signal "TOP")
		(4 "In1.Cu" signal "L2GND")
		(6 "In2.Cu" signal "L3")
		(8 "In3.Cu" signal "L4GND")
		(10 "In4.Cu" signal "L5")
		(12 "In5.Cu" signal "L6GND")
		(14 "In6.Cu" signal "L7VCC")
		(16 "In7.Cu" signal "L8VCC")
		(18 "In8.Cu" signal "L9GND")
		(20 "In9.Cu" signal "L10")
		(22 "In10.Cu" signal "L11GND")
		(24 "In11.Cu" signal "L12")
		(26 "In12.Cu" signal "L13GND")
		(2 "B.Cu" signal "BOTTOM")
		(9 "F.Adhes" user "F.Adhesive")
		(11 "B.Adhes" user "B.Adhesive")
		(13 "F.Paste" user "Package Geometry/Pastemask Top")
		(15 "B.Paste" user "Package Geometry/Pastemask Bottom")
		(5 "F.SilkS" user "Ref Des/Silkscreen Top")
		(7 "B.SilkS" user "Ref Des/Silkscreen Bottom")
		(1 "F.Mask" user "Board Geometry/Soldermask Top")
		(3 "B.Mask" user "Board Geometry/Soldermask Bottom")
		(17 "Dwgs.User" user "User.Drawings")
		(19 "Cmts.User" user "User.Comments")
		(21 "Eco1.User" user "User.Eco1")
		(23 "Eco2.User" user "User.Eco2")
		(25 "Edge.Cuts" user "Board Geometry/Outline")
		(27 "Margin" user)
		(31 "F.CrtYd" user "Package Geometry/Place Bound Top")
		(29 "B.CrtYd" user "Package Geometry/Place Bound Bottom")
		(35 "F.Fab" user "Ref Des/Assembly Top")
		(33 "B.Fab" user "Ref Des/Assembly Bottom")
	)
	(footprint ""
		(layer "B.Cu")
		(at 411.099 -141.0208 -90)
		(property "Reference" "C2L48"
			(at 0 0 90)
			(layer "B.SilkS")
			(hide yes)
			(effects
				(font
					(size 1.27 1.27)
				)
				(justify mirror)
			)
		)
		(property "Value" ""
			(at 0 0 90)
			(layer "B.Fab")
			(effects
				(font
					(size 1.27 1.27)
				)
				(justify mirror)
			)
		)
		(duplicate_pad_numbers_are_jumpers no)
		(fp_poly
			(pts
				(xy -0.3048 -0.1016) (xy -0.3048 0.9906) (xy 0.3048 0.9906) (xy 0.3048 -0.1016)
			)
			(stroke
				(width 0)
				(type default)
			)
			(fill no)
			(layer "B.CrtYd")
		)
		(fp_line
			(start -0.3048 0.9906)
			(end -0.3048 -0.1016)
			(stroke
				(width 0.1)
				(type default)
			)
			(layer "B.Fab")
		)
		(fp_line
			(start 0.3048 0.9906)
			(end -0.3048 0.9906)
			(stroke
				(width 0.1)
				(type default)
			)
			(layer "B.Fab")
		)
		(fp_line
			(start -0.3048 -0.1016)
			(end 0.3048 -0.1016)
			(stroke
				(width 0.1)
				(type default)
			)
			(layer "B.Fab")
		)
		(fp_line
			(start 0.3048 -0.1016)
			(end 0.3048 0.9906)
			(stroke
				(width 0.1)
				(type default)
			)
			(layer "B.Fab")
		)
		(pad "1" smd rect
			(at 0 0 90)
			(size 0.508 0.508)
			(layers "B.Cu" "B.Mask" "B.Paste")
			(net "SATA6G_P6_TX_C_DP")
		)
		(pad "2" smd rect
			(at 0 0.889 90)
			(size 0.508 0.508)
			(layers "B.Cu" "B.Mask" "B.Paste")
			(net "SATA6G_PCH_PCIE_UP_SATA_TXP<6>")
		)
		(zone
			(layer "B.Cu")
			(hatch none 0.5)
			(connect_pads
				(clearance 0)
			)
			(min_thickness 0.25)
			(keepout
				(tracks not_allowed)
				(vias allowed)
				(pads allowed)
				(copperpour not_allowed)
				(footprints allowed)
			)
			(placement
				(enabled no)
				(sheetname "")
			)
			(fill
				(thermal_gap 0.5)
				(thermal_bridge_width 0.5)
				(island_removal_mode 0)
			)
			(polygon
				(pts
					(xy 410.464 -140.7668) (xy 410.464 -141.2748) (xy 410.845 -141.2748) (xy 410.845 -140.7668)
				)
			)
		)
		(zone
			(layer "B.Cu")
			(hatch none 0.5)
			(connect_pads
				(clearance 0)
			)
			(min_thickness 0.25)
			(keepout
				(tracks allowed)
				(vias not_allowed)
				(pads allowed)
				(copperpour not_allowed)
				(footprints allowed)
			)
			(placement
				(enabled no)
				(sheetname "")
			)
			(fill
				(thermal_gap 0.5)
				(thermal_bridge_width 0.5)
				(island_removal_mode 0)
			)
			(polygon
				(pts
					(xy 410.845 -140.7668) (xy 410.845 -141.2748) (xy 410.464 -141.2748) (xy 410.464 -140.7668)
				)
			)
		)
	)
	(footprint ""
		(layer "B.Cu")
		(at 276.5806 -84.5312)
		(property "Reference" "C8W3"
			(at -1.47828 0.78994 90)
			(unlocked yes)
			(layer "B.SilkS")
			(effects
				(font
					(size 0.4064 0.254)
					(thickness 0.1524)
				)
				(justify mirror)
			)
		)
		(property "Value" ""
			(at 0 0 0)
			(layer "B.Fab")
			(effects
				(font
					(size 1.27 1.27)
				)
				(justify mirror)
			)
		)
		(duplicate_pad_numbers_are_jumpers no)
		(fp_poly
			(pts
				(xy 0.7239 -0.2159) (xy -0.7239 -0.2159) (xy -0.7239 1.9939) (xy 0.7239 1.9939)
			)
			(stroke
				(width 0)
				(type default)
			)
			(fill no)
			(layer "B.CrtYd")
		)
		(fp_line
			(start -0.7239 -0.2159)
			(end 0.7239 -0.2159)
			(stroke
				(width 0.1)
				(type default)
			)
			(layer "B.Fab")
		)
		(fp_line
			(start -0.7239 1.9939)
			(end -0.7239 -0.2159)
			(stroke
				(width 0.1)
				(type default)
			)
			(layer "B.Fab")
		)
		(fp_line
			(start 0.7239 -0.2159)
			(end 0.7239 1.9939)
			(stroke
				(width 0.1)
				(type default)
			)
			(layer "B.Fab")
		)
		(fp_line
			(start 0.7239 1.9939)
			(end -0.7239 1.9939)
			(stroke
				(width 0.1)
				(type default)
			)
			(layer "B.Fab")
		)
		(pad "1" smd rect
			(at 0 0 180)
			(size 1.27 1.016)
			(layers "B.Cu" "B.Mask" "B.Paste")
			(net "PVCCIN_CPU0")
		)
		(pad "2" smd rect
			(at 0 1.778 180)
			(size 1.27 1.016)
			(layers "B.Cu" "B.Mask" "B.Paste")
			(net "GND")
		)
		(zone
			(layer "B.Cu")
			(hatch none 0.5)
			(connect_pads
				(clearance 0)
			)
			(min_thickness 0.25)
			(keepout
				(tracks not_allowed)
				(vias allowed)
				(pads allowed)
				(copperpour not_allowed)
				(footprints allowed)
			)
			(placement
				(enabled no)
				(sheetname "")
			)
			(fill
				(thermal_gap 0.5)
				(thermal_bridge_width 0.5)
				(island_removal_mode 0)
			)
			(polygon
				(pts
					(xy 277.2156 -84.0232) (xy 275.9456 -84.0232) (xy 275.9456 -83.2612) (xy 277.2156 -83.2612)
				)
			)
		)
	)
	(footprint ""
		(layer "B.Cu")
		(at 361.444794 -47.258986 -90)
		(property "Reference" "R7D24"
			(at 0 0 90)
			(layer "B.SilkS")
			(hide yes)
			(effects
				(font
					(size 1.27 1.27)
				)
				(justify mirror)
			)
		)
		(property "Value" ""
			(at 0 0 90)
			(layer "B.Fab")
			(effects
				(font
					(size 1.27 1.27)
				)
				(justify mirror)
			)
		)
		(duplicate_pad_numbers_are_jumpers no)
		(fp_poly
			(pts
				(xy 0.2794 -0.1016) (xy -0.2794 -0.1016) (xy -0.2794 0.9906) (xy 0.2794 0.9906)
			)
			(stroke
				(width 0)
				(type default)
			)
			(fill no)
			(layer "B.CrtYd")
		)
		(fp_line
			(start -0.2794 0.9906)
			(end -0.2794 -0.1016)
			(stroke
				(width 0.1)
				(type default)
			)
			(layer "B.Fab")
		)
		(fp_line
			(start 0.2794 0.9906)
			(end -0.2794 0.9906)
			(stroke
				(width 0.1)
				(type default)
			)
			(layer "B.Fab")
		)
		(fp_line
			(start -0.2794 -0.1016)
			(end 0.2794 -0.1016)
			(stroke
				(width 0.1)
				(type default)
			)
			(layer "B.Fab")
		)
		(fp_line
			(start 0.2794 -0.1016)
			(end 0.2794 0.9906)
			(stroke
				(width 0.1)
				(type default)
			)
			(layer "B.Fab")
		)
		(pad "1" smd rect
			(at 0 0 90)
			(size 0.508 0.508)
			(layers "B.Cu" "B.Mask" "B.Paste")
			(net "FM_CPU1_PROCHOT_LVT3_K_N")
		)
		(pad "2" smd rect
			(at 0 0.889 90)
			(size 0.508 0.508)
			(layers "B.Cu" "B.Mask" "B.Paste")
			(net "FM_CPU1_PROCHOT_LVT3_N")
		)
		(zone
			(layer "B.Cu")
			(hatch none 0.5)
			(connect_pads
				(clearance 0)
			)
			(min_thickness 0.25)
			(keepout
				(tracks not_allowed)
				(vias allowed)
				(pads allowed)
				(copperpour not_allowed)
				(footprints allowed)
			)
			(placement
				(enabled no)
				(sheetname "")
			)
			(fill
				(thermal_gap 0.5)
				(thermal_bridge_width 0.5)
				(island_removal_mode 0)
			)
			(polygon
				(pts
					(xy 360.809794 -47.004986) (xy 360.809794 -47.512986) (xy 361.190794 -47.512986) (xy 361.190794 -47.004986)
				)
			)
		)
		(zone
			(layer "B.Cu")
			(hatch none 0.5)
			(connect_pads
				(clearance 0)
			)
			(min_thickness 0.25)
			(keepout
				(tracks allowed)
				(vias not_allowed)
				(pads allowed)
				(copperpour not_allowed)
				(footprints allowed)
			)
			(placement
				(enabled no)
				(sheetname "")
			)
			(fill
				(thermal_gap 0.5)
				(thermal_bridge_width 0.5)
				(island_removal_mode 0)
			)
			(polygon
				(pts
					(xy 361.190794 -47.004986) (xy 361.190794 -47.512986) (xy 360.809794 -47.512986) (xy 360.809794 -47.004986)
				)
			)
		)
	)
)
